(kicad_pcb
	(version 20260206)
	(generator "pcbnew")
	(generator_version "10.0")
	(general
		(thickness 1.6)
		(legacy_teardrops no)
	)
	(paper "A4")
	(title_block
		(title "Bryce Canyon_R.DPB_16317-1_OCP.brd")
		(comment 1 "Bryce Canyon / footprints 1397-1401 of 2099")
	)
	(layers
		(0 "F.Cu" signal "TOP")
		(4 "In1.Cu" signal "L2GND")
		(6 "In2.Cu" signal "L3")
		(8 "In3.Cu" signal "L4VCC")
		(10 "In4.Cu" signal "L5VCC")
		(12 "In5.Cu" signal "L6")
		(14 "In6.Cu" signal "L7GND")
		(2 "B.Cu" signal "BOTTOM")
		(9 "F.Adhes" user "F.Adhesive")
		(11 "B.Adhes" user "B.Adhesive")
		(13 "F.Paste" user "Package Geometry/Pastemask Top")
		(15 "B.Paste" user "Package Geometry/Pastemask Bottom")
		(5 "F.SilkS" user "Ref Des/Silkscreen Top")
		(7 "B.SilkS" user "Ref Des/Silkscreen Bottom")
		(1 "F.Mask" user "Board Geometry/Soldermask Top")
		(3 "B.Mask" user "Board Geometry/Soldermask Bottom")
		(17 "Dwgs.User" user "User.Drawings")
		(19 "Cmts.User" user "User.Comments")
		(21 "Eco1.User" user "User.Eco1")
		(23 "Eco2.User" user "User.Eco2")
		(25 "Edge.Cuts" user "Board Geometry/Outline")
		(27 "Margin" user)
		(31 "F.CrtYd" user "Package Geometry/Place Bound Top")
		(29 "B.CrtYd" user "Package Geometry/Place Bound Bottom")
		(35 "F.Fab" user "Ref Des/Assembly Top")
		(33 "B.Fab" user "Ref Des/Assembly Bottom")
	)
	(footprint ""
		(layer "F.Cu")
		(at 305.408076 -327.858882)
		(property "Reference" "R98"
			(at 0 0 0)
			(layer "F.SilkS")
			(hide yes)
			(effects
				(font
					(size 1.27 1.27)
				)
			)
		)
		(property "Value" "100KR2F-L1-GP"
			(at 0.064008 -3.993896 0)
			(unlocked yes)
			(layer "F.Fab")
			(hide yes)
			(effects
				(font
					(size 1.016 1.016)
					(thickness 0.1524)
				)
			)
		)
		(property "Device Type" "R402H16"
			(at 0.064008 -5.517896 0)
			(unlocked yes)
			(layer "F.Fab")
			(hide yes)
			(effects
				(font
					(size 1.016 1.016)
					(thickness 0.1524)
				)
			)
		)
		(duplicate_pad_numbers_are_jumpers no)
		(fp_line
			(start -0.508 -0.9398)
			(end -0.508 0.9398)
			(stroke
				(width 0.1524)
				(type default)
			)
			(layer "F.SilkS")
		)
		(fp_line
			(start 0.508 -0.9398)
			(end -0.508 -0.9398)
			(stroke
				(width 0.1524)
				(type default)
			)
			(layer "F.SilkS")
		)
		(fp_rect
			(start -0.508 0.9398)
			(end 0.508 -0.9398)
			(stroke
				(width 0)
				(type default)
			)
			(fill no)
			(layer "F.CrtYd")
		)
		(fp_rect
			(start -0.508 0.9398)
			(end 0.508 -0.9398)
			(stroke
				(width 0)
				(type default)
			)
			(fill no)
			(layer "F.Fab")
		)
		(pad "1" smd custom
			(at 0 -0.4445)
			(size 0.1397 0.1397)
			(layers "F.Cu" "F.Mask" "F.Paste")
			(net "PWM_BMC_B_ZONE_C")
			(options
				(clearance outline)
				(anchor circle)
			)
			(primitives
				(gr_poly
					(pts
						(arc
							(start -0.1778 -0.2794)
							(mid -0.249642 -0.249642)
							(end -0.2794 -0.1778)
						)
						(arc
							(start -0.2794 0.1778)
							(mid -0.249642 0.249642)
							(end -0.1778 0.2794)
						)
						(arc
							(start 0.1778 0.2794)
							(mid 0.249642 0.249642)
							(end 0.2794 0.1778)
						)
						(arc
							(start 0.2794 -0.1778)
							(mid 0.249642 -0.249642)
							(end 0.1778 -0.2794)
						)
					)
					(width 0)
					(fill yes)
				)
			)
		)
		(pad "2" smd custom
			(at 0 0.4445)
			(size 0.1397 0.1397)
			(layers "F.Cu" "F.Mask" "F.Paste")
			(net "GND")
			(options
				(clearance outline)
				(anchor circle)
			)
			(primitives
				(gr_poly
					(pts
						(arc
							(start -0.1778 -0.2794)
							(mid -0.249642 -0.249642)
							(end -0.2794 -0.1778)
						)
						(arc
							(start -0.2794 0.1778)
							(mid -0.249642 0.249642)
							(end -0.1778 0.2794)
						)
						(arc
							(start 0.1778 0.2794)
							(mid 0.249642 0.249642)
							(end 0.2794 0.1778)
						)
						(arc
							(start 0.2794 -0.1778)
							(mid 0.249642 -0.249642)
							(end 0.1778 -0.2794)
						)
					)
					(width 0)
					(fill yes)
				)
			)
		)
	)
	(footprint ""
		(layer "F.Cu")
		(at 475.107 -146.939 -90)
		(property "Reference" "C330"
			(at 0 0 270)
			(layer "F.SilkS")
			(hide yes)
			(effects
				(font
					(size 1.27 1.27)
				)
			)
		)
		(property "Value" "SC10U16V6KX-2GP"
			(at -0.0762 -5.1308 270)
			(unlocked yes)
			(layer "F.Fab")
			(hide yes)
			(effects
				(font
					(size 1.016 1.016)
					(thickness 0.1524)
				)
			)
		)
		(property "Device Type" "C1206H71"
			(at -0.127 -6.6548 270)
			(unlocked yes)
			(layer "F.Fab")
			(hide yes)
			(effects
				(font
					(size 1.016 1.016)
					(thickness 0.1524)
				)
			)
		)
		(duplicate_pad_numbers_are_jumpers no)
		(fp_line
			(start -1.016 2.2352)
			(end -1.016 0.8382)
			(stroke
				(width 0.1524)
				(type default)
			)
			(layer "F.SilkS")
		)
		(fp_line
			(start 1.016 2.2352)
			(end -1.016 2.2352)
			(stroke
				(width 0.1524)
				(type default)
			)
			(layer "F.SilkS")
		)
		(fp_line
			(start 1.016 0.8382)
			(end 1.016 2.2352)
			(stroke
				(width 0.1524)
				(type default)
			)
			(layer "F.SilkS")
		)
		(fp_line
			(start -1.016 -0.8382)
			(end -1.016 -2.2352)
			(stroke
				(width 0.1524)
				(type default)
			)
			(layer "F.SilkS")
		)
		(fp_line
			(start -1.016 -2.2352)
			(end 1.016 -2.2352)
			(stroke
				(width 0.1524)
				(type default)
			)
			(layer "F.SilkS")
		)
		(fp_line
			(start 1.016 -2.2352)
			(end 1.016 -0.8382)
			(stroke
				(width 0.1524)
				(type default)
			)
			(layer "F.SilkS")
		)
		(fp_rect
			(start -1.0922 2.3114)
			(end 1.0922 -2.3114)
			(stroke
				(width 0)
				(type default)
			)
			(fill no)
			(layer "F.CrtYd")
		)
		(fp_poly
			(pts
				(xy 1.0922 -2.3114) (xy 1.0922 2.3114) (xy -1.0922 2.3114) (xy -1.0922 -2.3114)
			)
			(stroke
				(width 0)
				(type default)
			)
			(fill no)
			(layer "F.Fab")
		)
		(pad "1" smd rect
			(at 0 -1.397 270)
			(size 1.651 1.27)
			(layers "F.Cu" "F.Mask" "F.Paste")
			(net "P5V_HDD23")
		)
		(pad "2" smd rect
			(at 0 1.397 270)
			(size 1.651 1.27)
			(layers "F.Cu" "F.Mask" "F.Paste")
			(net "GND")
		)
	)
	(footprint ""
		(layer "F.Cu")
		(at 368.3 -263.017)
		(property "Reference" "Q28"
			(at 0 0 0)
			(layer "F.SilkS")
			(hide yes)
			(effects
				(font
					(size 1.27 1.27)
				)
			)
		)
		(property "Value" "AO4407AL-GP"
			(at -3.707384 -1.5367 0)
			(unlocked yes)
			(layer "F.Fab")
			(hide yes)
			(effects
				(font
					(size 1.016 1.016)
					(thickness 0.1524)
				)
			)
		)
		(property "Device Type" "SOIC8H69"
			(at -3.707384 -3.0607 0)
			(unlocked yes)
			(layer "F.Fab")
			(hide yes)
			(effects
				(font
					(size 1.016 1.016)
					(thickness 0.1524)
				)
			)
		)
		(duplicate_pad_numbers_are_jumpers no)
		(fp_line
			(start -2.7432 -1.4224)
			(end -2.7432 1.4224)
			(stroke
				(width 0.1524)
				(type default)
			)
			(layer "F.SilkS")
		)
		(fp_line
			(start -2.7432 1.4224)
			(end -2.6416 1.4224)
			(stroke
				(width 0.1524)
				(type default)
			)
			(layer "F.SilkS")
		)
		(fp_line
			(start -2.7432 1.4224)
			(end 2.1336 1.4224)
			(stroke
				(width 0.1524)
				(type default)
			)
			(layer "F.SilkS")
		)
		(fp_line
			(start -2.7178 -0.508)
			(end -2.1844 -0.0508)
			(stroke
				(width 0.1524)
				(type default)
			)
			(layer "F.SilkS")
		)
		(fp_line
			(start -2.6289 3.4417)
			(end -2.6289 1.4732)
			(stroke
				(width 0.381)
				(type default)
			)
			(layer "F.SilkS")
		)
		(fp_line
			(start -2.1844 -0.0508)
			(end -2.7178 0.508)
			(stroke
				(width 0.1524)
				(type default)
			)
			(layer "F.SilkS")
		)
		(fp_line
			(start 2.1336 -1.4224)
			(end -2.7432 -1.4224)
			(stroke
				(width 0.1524)
				(type default)
			)
			(layer "F.SilkS")
		)
		(fp_line
			(start 2.1336 1.4224)
			(end 2.1336 -1.4224)
			(stroke
				(width 0.1524)
				(type default)
			)
			(layer "F.SilkS")
		)
		(fp_poly
			(pts
				(xy -2.2098 -1.4224) (xy -2.2098 1.4224) (xy 2.2098 1.4224) (xy 2.2098 -1.4224)
			)
			(stroke
				(width 0)
				(type default)
			)
			(fill yes)
			(layer "F.SilkS")
		)
		(fp_rect
			(start -2.450084 2.999994)
			(end 2.450084 -2.999994)
			(stroke
				(width 0)
				(type default)
			)
			(fill no)
			(layer "F.CrtYd")
		)
		(fp_poly
			(pts
				(xy -2.8194 3.6322) (xy -2.8194 -3.6322) (xy 2.8194 -3.6322) (xy 2.8194 1.18364) (xy 2.450084 1.18364)
				(xy 2.450084 -2.999994) (xy -2.450084 -2.999994) (xy -2.450084 2.999994) (xy 2.450084 2.999994)
				(xy 2.450084 1.18618) (xy 2.8194 1.18618) (xy 2.8194 3.6322)
			)
			(stroke
				(width 0)
				(type default)
			)
			(fill no)
			(layer "F.CrtYd")
		)
		(fp_rect
			(start -2.8194 3.6322)
			(end 2.8194 -3.6322)
			(stroke
				(width 0)
				(type default)
			)
			(fill no)
			(layer "F.Fab")
		)
		(pad "1" smd rect
			(at -1.905 2.54)
			(size 0.635 1.651)
			(layers "F.Cu" "F.Mask" "F.Paste")
			(net "P12V_B")
		)
		(pad "2" smd rect
			(at -0.635 2.54)
			(size 0.635 1.651)
			(layers "F.Cu" "F.Mask" "F.Paste")
			(net "P12V_B")
		)
		(pad "3" smd rect
			(at 0.635 2.54)
			(size 0.635 1.651)
			(layers "F.Cu" "F.Mask" "F.Paste")
			(net "P12V_B")
		)
		(pad "4" smd rect
			(at 1.905 2.54)
			(size 0.635 1.651)
			(layers "F.Cu" "F.Mask" "F.Paste")
			(net "SW_HDD_N7")
		)
		(pad "5" smd rect
			(at 1.905 -2.54)
			(size 0.635 1.651)
			(layers "F.Cu" "F.Mask" "F.Paste")
			(net "P12V_HDD7")
		)
		(pad "6" smd rect
			(at 0.635 -2.54)
			(size 0.635 1.651)
			(layers "F.Cu" "F.Mask" "F.Paste")
			(net "P12V_HDD7")
		)
		(pad "7" smd rect
			(at -0.635 -2.54)
			(size 0.635 1.651)
			(layers "F.Cu" "F.Mask" "F.Paste")
			(net "P12V_HDD7")
		)
		(pad "8" smd rect
			(at -1.905 -2.54)
			(size 0.635 1.651)
			(layers "F.Cu" "F.Mask" "F.Paste")
			(net "P12V_HDD7")
		)
	)
	(footprint ""
		(layer "F.Cu")
		(at 192.513966 -154.70505)
		(property "Reference" "TP106"
			(at 0 0 0)
			(layer "F.SilkS")
			(hide yes)
			(effects
				(font
					(size 1.27 1.27)
				)
			)
		)
		(property "Value" "*"
			(at -0.0508 -1.6764 0)
			(unlocked yes)
			(layer "F.Fab")
			(hide yes)
			(effects
				(font
					(size 1.016 1.016)
					(thickness 0.1524)
				)
			)
		)
		(property "Device Type" "TPAD32"
			(at -0.0508 -3.2004 0)
			(unlocked yes)
			(layer "F.Fab")
			(hide yes)
			(effects
				(font
					(size 1.016 1.016)
					(thickness 0.1524)
				)
			)
		)
		(duplicate_pad_numbers_are_jumpers no)
		(fp_poly
			(pts
				(arc
					(start 0.4064 0)
					(mid -0.4064 0)
					(end 0.4064 0)
				)
			)
			(stroke
				(width 0)
				(type default)
			)
			(fill no)
			(layer "F.CrtYd")
		)
		(fp_poly
			(pts
				(arc
					(start 0.7112 0)
					(mid -0.7112 0)
					(end 0.7112 0)
				)
			)
			(stroke
				(width 0)
				(type default)
			)
			(fill no)
			(layer "F.Fab")
		)
		(pad "1" smd circle
			(at 0 0)
			(size 0.8128 0.8128)
			(layers "F.Cu" "F.Mask" "F.Paste")
			(net "ACT_HDD_17")
		)
	)
	(footprint ""
		(layer "F.Cu")
		(at 109.1946 -99.7204 180)
		(property "Reference" "Q234"
			(at 0 0 180)
			(layer "F.SilkS")
			(hide yes)
			(effects
				(font
					(size 1.27 1.27)
				)
			)
		)
		(property "Value" "2N7002K-2-GP"
			(at 0.127 -8.9662 180)
			(unlocked yes)
			(layer "F.Fab")
			(hide yes)
			(effects
				(font
					(size 1.016 1.016)
					(thickness 0.1524)
				)
			)
		)
		(property "Device Type" "SOT23DGS2D4H44"
			(at 0.127 -10.4902 180)
			(unlocked yes)
			(layer "F.Fab")
			(hide yes)
			(effects
				(font
					(size 1.016 1.016)
					(thickness 0.1524)
				)
			)
		)
		(duplicate_pad_numbers_are_jumpers no)
		(fp_line
			(start 1.651 1.778)
			(end 1.651 -1.778)
			(stroke
				(width 0.1524)
				(type default)
			)
			(layer "F.SilkS")
		)
		(fp_line
			(start 1.651 -1.778)
			(end -1.651 -1.778)
			(stroke
				(width 0.1524)
				(type default)
			)
			(layer "F.SilkS")
		)
		(fp_line
			(start -1.651 1.778)
			(end 1.651 1.778)
			(stroke
				(width 0.1524)
				(type default)
			)
			(layer "F.SilkS")
		)
		(fp_line
			(start -1.651 -1.778)
			(end -1.651 1.778)
			(stroke
				(width 0.1524)
				(type default)
			)
			(layer "F.SilkS")
		)
		(fp_poly
			(pts
				(xy -1.778 1.8796) (xy -1.778 -1.8796) (xy 1.778 -1.8796) (xy 1.778 1.8796)
			)
			(stroke
				(width 0)
				(type default)
			)
			(fill no)
			(layer "F.CrtYd")
		)
		(fp_poly
			(pts
				(xy -1.778 1.8796) (xy -1.778 -1.8796) (xy 1.778 -1.8796) (xy 1.778 1.8796)
			)
			(stroke
				(width 0)
				(type default)
			)
			(fill no)
			(layer "F.Fab")
		)
		(pad "D" smd custom
			(at 0 -0.9525 180)
			(size 0.1905 0.1905)
			(layers "F.Cu" "F.Mask" "F.Paste")
			(net "FLT_HDD15_N")
			(options
				(clearance outline)
				(anchor circle)
			)
			(primitives
				(gr_poly
					(pts
						(arc
							(start -0.1778 0.5715)
							(mid -0.321484 0.511984)
							(end -0.381 0.3683)
						)
						(arc
							(start -0.381 -0.3683)
							(mid -0.321484 -0.511984)
							(end -0.1778 -0.5715)
						)
						(arc
							(start 0.1778 -0.5715)
							(mid 0.321484 -0.511984)
							(end 0.381 -0.3683)
						)
						(arc
							(start 0.381 0.3683)
							(mid 0.321484 0.511984)
							(end 0.1778 0.5715)
						)
					)
					(width 0)
					(fill yes)
				)
			)
		)
		(pad "G" smd custom
			(at -0.98425 0.9525 180)
			(size 0.1905 0.1905)
			(layers "F.Cu" "F.Mask" "F.Paste")
			(net "DRIVE_B_15_FLT_LED")
			(options
				(clearance outline)
				(anchor circle)
			)
			(primitives
				(gr_poly
					(pts
						(arc
							(start -0.1778 0.5715)
							(mid -0.321484 0.511984)
							(end -0.381 0.3683)
						)
						(arc
							(start -0.381 -0.3683)
							(mid -0.321484 -0.511984)
							(end -0.1778 -0.5715)
						)
						(arc
							(start 0.1778 -0.5715)
							(mid 0.321484 -0.511984)
							(end 0.381 -0.3683)
						)
						(arc
							(start 0.381 0.3683)
							(mid 0.321484 0.511984)
							(end 0.1778 0.5715)
						)
					)
					(width 0)
					(fill yes)
				)
			)
		)
		(pad "S" smd custom
			(at 0.98425 0.9525 180)
			(size 0.1905 0.1905)
			(layers "F.Cu" "F.Mask" "F.Paste")
			(net "GND")
			(options
				(clearance outline)
				(anchor circle)
			)
			(primitives
				(gr_poly
					(pts
						(arc
							(start -0.1778 0.5715)
							(mid -0.321484 0.511984)
							(end -0.381 0.3683)
						)
						(arc
							(start -0.381 -0.3683)
							(mid -0.321484 -0.511984)
							(end -0.1778 -0.5715)
						)
						(arc
							(start 0.1778 -0.5715)
							(mid 0.321484 -0.511984)
							(end 0.381 -0.3683)
						)
						(arc
							(start 0.381 0.3683)
							(mid 0.321484 0.511984)
							(end 0.1778 0.5715)
						)
					)
					(width 0)
					(fill yes)
				)
			)
		)
	)
)
